# Stackup_grand teton_MB_18L_2p413mm_EM-890K_VL411_Rev0p6_20230202.xls — Stackup (pcb-stackup)
| STACKUP |  |  |  | Target Z (ohms) - MicroStrip |  |  |  |  | 40 | 45 | 50 | Breakout | 85 |  | 93 |  | 100 |  |  |  | Breakout |  |
|  |  |  |  | Target Z (ohms) - StripLine |  |  |  |  | 40 | 45 | 50 |  | 85 |  | 93 |  | 100 |  | 93(Breakout region) |  |  |  |
|  |  |  |  | Z tolerance |  |  |  |  | 0.1 | 0.1 | 0.1 |  | 0.1 |  | 0.1 |  | 0.1 |  | 0.1 |  |  |  |
|  |  |  |  | Z Type |  |  |  |  | Single | Single | Single | Single | Differential |  | Differential |  | Differential |  | Differential |  | Differential |  |
| Layer# | Material | Description |  | Copper Weight (oz) | Thickness (mil) | Tolerance (mil) | Glass Fabric | Er | Width | Width | Width | Width | Width | Space | Width | Space | Width | Space | Width | Space | Width | Space |
|  |  |  | Soldermask |  | 0.6 |  |  | 3.8 |  |  |  |  |  |  |  |  |  |  |  |  |  |  |
| 1 |  |  | TOP | 0.5+plating | 1.95 |  |  |  | 7.9 | 6.3 | 5.1 | 3.5 | 5.2 | 5 | 5 | 8.5 | 4.4 | 9.5 |  |  | 3.5 | 4 |
|  | EM-890K |  | PP |  | 2.7 | ±0.709 | 1078x1 | 2.92 |  |  |  |  |  |  |  |  |  |  |  |  |  |  |
| 2 |  |  | GND | 0.5 (VL411) | 0.65 |  |  |  |  |  |  |  |  |  |  |  |  |  |  |  |  |  |
|  | EM-890K |  | CORE |  | 4 | ±0.709 | 1078x1 | 2.93 |  |  |  |  |  |  |  |  |  |  |  |  |  |  |
| 3 |  |  | IN1 | 1 (VL411) | 1.3 |  |  |  | 7.2 | 6.1 | 5 | 3.5 | 5.8 | 5 | 5.5 | 9.1 | 4.9 | 11.8 | 4 | 3 | 3.5 | 4 |
|  | EM-890K |  | PP |  | 5 | ±0.984 | 1078x2 | 2.94 |  |  |  |  |  |  |  |  |  |  |  |  |  |  |
| 4 |  |  | GND1 | 0.5 (VL411) | 0.65 |  |  |  |  |  |  |  |  |  |  |  |  |  |  |  |  |  |
|  | EM-890K |  | CORE |  | 4 | ±0.709 | 1078x1 | 2.93 |  |  |  |  |  |  |  |  |  |  |  |  |  |  |
| 5 |  |  | IN2 | 1 (VL411) | 1.3 |  |  |  | 7.2 | 6.1 | 5 | 3.5 | 5.8 | 5 | 5.5 | 9.1 | 4.9 | 11.8 | 4 | 3 | 3.5 | 4 |
|  | EM-890K |  | PP |  | 5 | ±0.984 | 1078x2 | 2.94 |  |  |  |  |  |  |  |  |  |  |  |  |  |  |
| 6 |  |  | GND2 | 0.5 (VL411) | 0.65 |  |  |  |  |  |  |  |  |  |  |  |  |  |  |  |  |  |
|  | EM-890K |  | CORE |  | 4 | ±0.709 | 1078x1 | 2.93 |  |  |  |  |  |  |  |  |  |  |  |  |  |  |
| 7 |  |  | IN3 | 1 (VL411) | 1.3 |  |  |  | 7.2 | 6.1 | 5 | 3.5 | 5.8 | 5 | 5.5 | 9.1 | 4.9 | 11.8 | 4 | 3 | 3.5 | 4 |
|  | EM-890K |  | PP |  | 5 | ±0.984 | 1078x2 | 2.94 |  |  |  |  |  |  |  |  |  |  |  |  |  |  |
| 8 |  |  | GND3 | 1 (VL411) | 1.3 |  |  |  |  |  |  |  |  |  |  |  |  |  |  |  |  |  |
|  | EM-890K |  | CORE |  | 3.5 | ±0.709 | 1078x1 | 2.93 |  |  |  |  |  |  |  |  |  |  |  |  |  |  |
| 9 |  |  | VCC | 2 (RTF) | 2.6 |  |  |  |  |  |  |  |  |  |  |  |  |  |  |  |  |  |
|  | EM-890K |  | PP |  | 4 | ±0.709 | 1080x2 | 2.93 |  |  |  |  |  |  |  |  |  |  |  |  |  |  |
| 10 |  |  | VCC1 | 2 (RTF) | 2.6 |  |  |  |  |  |  |  |  |  |  |  |  |  |  |  |  |  |
|  | EM-890K |  | CORE |  | 3.5 | ±0.709 | 1078x1 | 2.93 |  |  |  |  |  |  |  |  |  |  |  |  |  |  |
| 11 |  |  | GND4 | 1 (VL411) | 1.3 |  |  |  |  |  |  |  |  |  |  |  |  |  |  |  |  |  |
|  | EM-890K |  | PP |  | 5 | ±0.984 | 1078x2 | 2.94 |  |  |  |  |  |  |  |  |  |  |  |  |  |  |
| 12 |  |  | IN4 | 1 (VL411) | 1.3 |  |  |  | 7.2 | 6.1 | 5 | 3.5 | 5.8 | 5 | 5.5 | 9.1 | 4.9 | 11.8 | 4 | 3 | 3.5 | 4 |
|  | EM-890K |  | CORE |  | 4 | ±0.709 | 1078x1 | 2.93 |  |  |  |  |  |  |  |  |  |  |  |  |  |  |
| 13 |  |  | GND5 | 0.5 (VL411) | 0.65 |  |  |  |  |  |  |  |  |  |  |  |  |  |  |  |  |  |
|  | EM-890K |  | PP |  | 5 | ±0.984 | 1078x2 | 2.94 |  |  |  |  |  |  |  |  |  |  |  |  |  |  |
| 14 |  |  | IN5 | 1 (VL411) | 1.3 |  |  |  | 7.2 | 6.1 | 5 | 3.5 | 5.8 | 5 | 5.5 | 9.1 | 4.9 | 11.8 | 4 | 3 | 3.5 | 4 |
|  | EM-890K |  | CORE |  | 4 | ±0.709 | 1078x1 | 2.93 |  |  |  |  |  |  |  |  |  |  |  |  |  |  |
| 15 |  |  | GND6 | 0.5 (VL411) | 0.65 |  |  |  |  |  |  |  |  |  |  |  |  |  |  |  |  |  |
|  | EM-890K |  | PP |  | 5 | ±0.984 | 1078x2 | 2.94 |  |  |  |  |  |  |  |  |  |  |  |  |  |  |
| 16 |  |  | IN6 | 1 (VL411) | 1.3 |  |  |  | 7.2 | 6.1 | 5 | 3.5 | 5.8 | 5 | 5.5 | 9.1 | 4.9 | 11.8 | 4 | 3 | 3.5 | 4 |
|  | EM-890K |  | CORE |  | 4 | ±0.709 | 1078x1 | 2.93 |  |  |  |  |  |  |  |  |  |  |  |  |  |  |
| 17 |  |  | GND7 | 0.5 (VL411) | 0.65 |  |  |  |  |  |  |  |  |  |  |  |  |  |  |  |  |  |
|  | EM-890K |  | PP |  | 2.7 | ±0.709 | 1078x1 | 2.92 |  |  |  |  |  |  |  |  |  |  |  |  |  |  |
| 18 |  |  | BOTTOM | 0.5+plating | 1.95 |  |  |  | 7.9 | 6.3 | 5.1 | 3.5 | 5.2 | 5 | 5 | 8.5 | 4.4 | 9.5 |  |  | 3.5 | 4 |
|  |  |  | Soldermask |  | 0.6 |  |  | 3.8 |  |  |  |  |  |  |  |  |  |  |  |  |  |  |
|  |  |  |  | Total | 95 | ±10% |  |  |  |  |  |  |  |  |  |  |  |  |  |  |  |  |
